(kicad_pcb
	(version 20260206)
	(generator "pcbnew")
	(generator_version "10.0")
	(general
		(thickness 1.6)
		(legacy_teardrops no)
	)
	(paper "A4")
	(title_block
		(title "panther-plus-userver — 13130-1b_20150205.brd")
		(comment 1 "Honey Badger (Wiwynn) / footprints 316-323 of 1509")
	)
	(layers
		(0 "F.Cu" signal "TOP")
		(4 "In1.Cu" signal "L2")
		(6 "In2.Cu" signal "L3")
		(8 "In3.Cu" signal "L4")
		(10 "In4.Cu" signal "L5")
		(12 "In5.Cu" signal "L6")
		(14 "In6.Cu" signal "L7")
		(16 "In7.Cu" signal "L8")
		(18 "In8.Cu" signal "L9")
		(20 "In9.Cu" signal "L10")
		(22 "In10.Cu" signal "L11")
		(2 "B.Cu" signal "BOTTOM")
		(9 "F.Adhes" user "F.Adhesive")
		(11 "B.Adhes" user "B.Adhesive")
		(13 "F.Paste" user "Package Geometry/Pastemask Top")
		(15 "B.Paste" user "Package Geometry/Pastemask Bottom")
		(5 "F.SilkS" user "Ref Des/Silkscreen Top")
		(7 "B.SilkS" user "Ref Des/Silkscreen Bottom")
		(1 "F.Mask" user "Board Geometry/Soldermask Top")
		(3 "B.Mask" user "Board Geometry/Soldermask Bottom")
		(17 "Dwgs.User" user "User.Drawings")
		(19 "Cmts.User" user "User.Comments")
		(21 "Eco1.User" user "User.Eco1")
		(23 "Eco2.User" user "User.Eco2")
		(25 "Edge.Cuts" user "Board Geometry/Outline")
		(27 "Margin" user)
		(31 "F.CrtYd" user "Package Geometry/Place Bound Top")
		(29 "B.CrtYd" user "Package Geometry/Place Bound Bottom")
		(35 "F.Fab" user "Ref Des/Assembly Top")
		(33 "B.Fab" user "Ref Des/Assembly Bottom")
	)
	(footprint ""
		(layer "F.Cu")
		(at 34.163 -68.326 90)
		(property "Reference" "PR19"
			(at 0 0 90)
			(layer "F.SilkS")
			(hide yes)
			(effects
				(font
					(size 1.27 1.27)
				)
			)
		)
		(property "Value" "10KR2F-2-GP"
			(at 1.7907 -1.1176 90)
			(unlocked yes)
			(layer "F.Fab")
			(hide yes)
			(effects
				(font
					(size 1.016 1.016)
					(thickness 0.1524)
				)
			)
		)
		(property "Device Type" "R402H16"
			(at 1.7907 -2.6416 90)
			(unlocked yes)
			(layer "F.Fab")
			(hide yes)
			(effects
				(font
					(size 1.016 1.016)
					(thickness 0.1524)
				)
			)
		)
		(duplicate_pad_numbers_are_jumpers no)
		(fp_rect
			(start -0.381 0.8382)
			(end 0.381 -0.8382)
			(stroke
				(width 0)
				(type default)
			)
			(fill no)
			(layer "F.CrtYd")
		)
		(fp_rect
			(start -0.381 0.8382)
			(end 0.381 -0.8382)
			(stroke
				(width 0)
				(type default)
			)
			(fill no)
			(layer "F.Fab")
		)
		(pad "1" smd custom
			(at 0 -0.4318 90)
			(size 0.127 0.127)
			(layers "F.Cu" "F.Mask" "F.Paste")
			(net "VR_PVNN_LH_R")
			(options
				(clearance outline)
				(anchor circle)
			)
			(primitives
				(gr_poly
					(pts
						(arc
							(start -0.2032 -0.2794)
							(mid -0.239121 -0.264521)
							(end -0.254 -0.2286)
						)
						(arc
							(start -0.254 0.2286)
							(mid -0.239121 0.264521)
							(end -0.2032 0.2794)
						)
						(arc
							(start 0.2032 0.2794)
							(mid 0.239121 0.264521)
							(end 0.254 0.2286)
						)
						(arc
							(start 0.254 -0.2286)
							(mid 0.239121 -0.264521)
							(end 0.2032 -0.2794)
						)
					)
					(width 0)
					(fill yes)
				)
			)
		)
		(pad "2" smd custom
			(at 0 0.4318 90)
			(size 0.127 0.127)
			(layers "F.Cu" "F.Mask" "F.Paste")
			(net "GND")
			(options
				(clearance outline)
				(anchor circle)
			)
			(primitives
				(gr_poly
					(pts
						(arc
							(start -0.2032 -0.2794)
							(mid -0.239121 -0.264521)
							(end -0.254 -0.2286)
						)
						(arc
							(start -0.254 0.2286)
							(mid -0.239121 0.264521)
							(end -0.2032 0.2794)
						)
						(arc
							(start 0.2032 0.2794)
							(mid 0.239121 0.264521)
							(end 0.254 0.2286)
						)
						(arc
							(start 0.254 -0.2286)
							(mid 0.239121 -0.264521)
							(end 0.2032 -0.2794)
						)
					)
					(width 0)
					(fill yes)
				)
			)
		)
	)
	(footprint ""
		(layer "F.Cu")
		(at 69.3166 -42.2402 -90)
		(property "Reference" "R316"
			(at 0 0 270)
			(layer "F.SilkS")
			(hide yes)
			(effects
				(font
					(size 1.27 1.27)
				)
			)
		)
		(property "Value" "4K7R2F-GP"
			(at 0.064008 -3.993896 270)
			(unlocked yes)
			(layer "F.Fab")
			(hide yes)
			(effects
				(font
					(size 1.016 1.016)
					(thickness 0.1524)
				)
			)
		)
		(property "Device Type" "R402H16"
			(at 0.064008 -5.517896 270)
			(unlocked yes)
			(layer "F.Fab")
			(hide yes)
			(effects
				(font
					(size 1.016 1.016)
					(thickness 0.1524)
				)
			)
		)
		(duplicate_pad_numbers_are_jumpers no)
		(fp_rect
			(start -0.381 0.8382)
			(end 0.381 -0.8382)
			(stroke
				(width 0)
				(type default)
			)
			(fill no)
			(layer "F.CrtYd")
		)
		(fp_rect
			(start -0.381 0.8382)
			(end 0.381 -0.8382)
			(stroke
				(width 0)
				(type default)
			)
			(fill no)
			(layer "F.Fab")
		)
		(pad "1" smd custom
			(at 0 -0.4318 270)
			(size 0.127 0.127)
			(layers "F.Cu" "F.Mask" "F.Paste")
			(net "P3V3")
			(options
				(clearance outline)
				(anchor circle)
			)
			(primitives
				(gr_poly
					(pts
						(arc
							(start -0.2032 -0.2794)
							(mid -0.239121 -0.264521)
							(end -0.254 -0.2286)
						)
						(arc
							(start -0.254 0.2286)
							(mid -0.239121 0.264521)
							(end -0.2032 0.2794)
						)
						(arc
							(start 0.2032 0.2794)
							(mid 0.239121 0.264521)
							(end 0.254 0.2286)
						)
						(arc
							(start 0.254 -0.2286)
							(mid 0.239121 -0.264521)
							(end 0.2032 -0.2794)
						)
					)
					(width 0)
					(fill yes)
				)
			)
		)
		(pad "2" smd custom
			(at 0 0.4318 270)
			(size 0.127 0.127)
			(layers "F.Cu" "F.Mask" "F.Paste")
			(net "SMBUS_HOST_CLK")
			(options
				(clearance outline)
				(anchor circle)
			)
			(primitives
				(gr_poly
					(pts
						(arc
							(start -0.2032 -0.2794)
							(mid -0.239121 -0.264521)
							(end -0.254 -0.2286)
						)
						(arc
							(start -0.254 0.2286)
							(mid -0.239121 0.264521)
							(end -0.2032 0.2794)
						)
						(arc
							(start 0.2032 0.2794)
							(mid 0.239121 0.264521)
							(end 0.254 0.2286)
						)
						(arc
							(start 0.254 -0.2286)
							(mid 0.239121 -0.264521)
							(end 0.2032 -0.2794)
						)
					)
					(width 0)
					(fill yes)
				)
			)
		)
	)
	(footprint ""
		(layer "F.Cu")
		(at 26.416 -50.8 -90)
		(property "Reference" "PR73"
			(at 0 0 270)
			(layer "F.SilkS")
			(hide yes)
			(effects
				(font
					(size 1.27 1.27)
				)
			)
		)
		(property "Value" "11KR2F-L-GP"
			(at 1.7907 -1.1176 270)
			(unlocked yes)
			(layer "F.Fab")
			(hide yes)
			(effects
				(font
					(size 1.016 1.016)
					(thickness 0.1524)
				)
			)
		)
		(property "Device Type" "R402H16"
			(at 1.7907 -2.6416 270)
			(unlocked yes)
			(layer "F.Fab")
			(hide yes)
			(effects
				(font
					(size 1.016 1.016)
					(thickness 0.1524)
				)
			)
		)
		(duplicate_pad_numbers_are_jumpers no)
		(fp_rect
			(start -0.381 0.8382)
			(end 0.381 -0.8382)
			(stroke
				(width 0)
				(type default)
			)
			(fill no)
			(layer "F.CrtYd")
		)
		(fp_rect
			(start -0.381 0.8382)
			(end 0.381 -0.8382)
			(stroke
				(width 0)
				(type default)
			)
			(fill no)
			(layer "F.Fab")
		)
		(pad "1" smd custom
			(at 0 -0.4318 270)
			(size 0.127 0.127)
			(layers "F.Cu" "F.Mask" "F.Paste")
			(net "VR_PVCCP_ISUMP")
			(options
				(clearance outline)
				(anchor circle)
			)
			(primitives
				(gr_poly
					(pts
						(arc
							(start -0.2032 -0.2794)
							(mid -0.239121 -0.264521)
							(end -0.254 -0.2286)
						)
						(arc
							(start -0.254 0.2286)
							(mid -0.239121 0.264521)
							(end -0.2032 0.2794)
						)
						(arc
							(start 0.2032 0.2794)
							(mid 0.239121 0.264521)
							(end 0.254 0.2286)
						)
						(arc
							(start 0.254 -0.2286)
							(mid 0.239121 -0.264521)
							(end 0.2032 -0.2794)
						)
					)
					(width 0)
					(fill yes)
				)
			)
		)
		(pad "2" smd custom
			(at 0 0.4318 270)
			(size 0.127 0.127)
			(layers "F.Cu" "F.Mask" "F.Paste")
			(net "VR_PVCCP_ISUMN")
			(options
				(clearance outline)
				(anchor circle)
			)
			(primitives
				(gr_poly
					(pts
						(arc
							(start -0.2032 -0.2794)
							(mid -0.239121 -0.264521)
							(end -0.254 -0.2286)
						)
						(arc
							(start -0.254 0.2286)
							(mid -0.239121 0.264521)
							(end -0.2032 0.2794)
						)
						(arc
							(start 0.2032 0.2794)
							(mid 0.239121 0.264521)
							(end 0.254 0.2286)
						)
						(arc
							(start 0.254 -0.2286)
							(mid 0.239121 -0.264521)
							(end 0.2032 -0.2794)
						)
					)
					(width 0)
					(fill yes)
				)
			)
		)
	)
	(footprint ""
		(layer "F.Cu")
		(at 13.8938 -68.8594 180)
		(property "Reference" "C170"
			(at 0 0 180)
			(layer "F.SilkS")
			(hide yes)
			(effects
				(font
					(size 1.27 1.27)
				)
			)
		)
		(property "Value" "SCD1U16V2KX-3GP"
			(at 1.8923 -1.2065 180)
			(unlocked yes)
			(layer "F.Fab")
			(hide yes)
			(effects
				(font
					(size 1.016 1.016)
					(thickness 0.1524)
				)
			)
		)
		(property "Device Type" "C402H22"
			(at 1.8923 -2.7305 180)
			(unlocked yes)
			(layer "F.Fab")
			(hide yes)
			(effects
				(font
					(size 1.016 1.016)
					(thickness 0.1524)
				)
			)
		)
		(duplicate_pad_numbers_are_jumpers no)
		(fp_rect
			(start -0.381 0.7366)
			(end 0.381 -0.7366)
			(stroke
				(width 0)
				(type default)
			)
			(fill no)
			(layer "F.CrtYd")
		)
		(fp_rect
			(start -0.381 0.7366)
			(end 0.381 -0.7366)
			(stroke
				(width 0)
				(type default)
			)
			(fill no)
			(layer "F.Fab")
		)
		(pad "1" smd custom
			(at 0 -0.4572 180)
			(size 0.1143 0.1143)
			(layers "F.Cu" "F.Mask" "F.Paste")
			(net "P3V3")
			(options
				(clearance outline)
				(anchor circle)
			)
			(primitives
				(gr_poly
					(pts
						(arc
							(start -0.254 -0.1778)
							(mid -0.239121 -0.213721)
							(end -0.2032 -0.2286)
						)
						(arc
							(start 0.2032 -0.2286)
							(mid 0.239121 -0.213721)
							(end 0.254 -0.1778)
						)
						(arc
							(start 0.254 0.1778)
							(mid 0.239121 0.213721)
							(end 0.2032 0.2286)
						)
						(arc
							(start -0.2032 0.2286)
							(mid -0.239121 0.213721)
							(end -0.254 0.1778)
						)
					)
					(width 0)
					(fill yes)
				)
			)
		)
		(pad "2" smd custom
			(at 0 0.4572 180)
			(size 0.1143 0.1143)
			(layers "F.Cu" "F.Mask" "F.Paste")
			(net "GND")
			(options
				(clearance outline)
				(anchor circle)
			)
			(primitives
				(gr_poly
					(pts
						(arc
							(start -0.254 -0.1778)
							(mid -0.239121 -0.213721)
							(end -0.2032 -0.2286)
						)
						(arc
							(start 0.2032 -0.2286)
							(mid 0.239121 -0.213721)
							(end 0.254 -0.1778)
						)
						(arc
							(start 0.254 0.1778)
							(mid 0.239121 0.213721)
							(end 0.2032 0.2286)
						)
						(arc
							(start -0.2032 0.2286)
							(mid -0.239121 0.213721)
							(end -0.254 0.1778)
						)
					)
					(width 0)
					(fill yes)
				)
			)
		)
	)
	(footprint ""
		(layer "F.Cu")
		(at 151.003 -20.701)
		(property "Reference" "C54"
			(at 0 0 0)
			(layer "F.SilkS")
			(hide yes)
			(effects
				(font
					(size 1.27 1.27)
				)
			)
		)
		(property "Value" "SCD1U10V2KX-5GP"
			(at 1.1811 -2.7051 0)
			(unlocked yes)
			(layer "F.Fab")
			(hide yes)
			(effects
				(font
					(size 1.016 1.016)
					(thickness 0.1524)
				)
			)
		)
		(property "Device Type" "C402H22"
			(at 1.1811 -4.2291 0)
			(unlocked yes)
			(layer "F.Fab")
			(hide yes)
			(effects
				(font
					(size 1.016 1.016)
					(thickness 0.1524)
				)
			)
		)
		(duplicate_pad_numbers_are_jumpers no)
		(fp_rect
			(start -0.381 0.7366)
			(end 0.381 -0.7366)
			(stroke
				(width 0)
				(type default)
			)
			(fill no)
			(layer "F.CrtYd")
		)
		(fp_rect
			(start -0.381 0.7366)
			(end 0.381 -0.7366)
			(stroke
				(width 0)
				(type default)
			)
			(fill no)
			(layer "F.Fab")
		)
		(pad "1" smd custom
			(at 0 -0.4572)
			(size 0.1143 0.1143)
			(layers "F.Cu" "F.Mask" "F.Paste")
			(net "P2V5_STBY")
			(options
				(clearance outline)
				(anchor circle)
			)
			(primitives
				(gr_poly
					(pts
						(arc
							(start -0.254 -0.1778)
							(mid -0.239121 -0.213721)
							(end -0.2032 -0.2286)
						)
						(arc
							(start 0.2032 -0.2286)
							(mid 0.239121 -0.213721)
							(end 0.254 -0.1778)
						)
						(arc
							(start 0.254 0.1778)
							(mid 0.239121 0.213721)
							(end 0.2032 0.2286)
						)
						(arc
							(start -0.2032 0.2286)
							(mid -0.239121 0.213721)
							(end -0.254 0.1778)
						)
					)
					(width 0)
					(fill yes)
				)
			)
		)
		(pad "2" smd custom
			(at 0 0.4572)
			(size 0.1143 0.1143)
			(layers "F.Cu" "F.Mask" "F.Paste")
			(net "GND")
			(options
				(clearance outline)
				(anchor circle)
			)
			(primitives
				(gr_poly
					(pts
						(arc
							(start -0.254 -0.1778)
							(mid -0.239121 -0.213721)
							(end -0.2032 -0.2286)
						)
						(arc
							(start 0.2032 -0.2286)
							(mid 0.239121 -0.213721)
							(end 0.254 -0.1778)
						)
						(arc
							(start 0.254 0.1778)
							(mid 0.239121 0.213721)
							(end 0.2032 0.2286)
						)
						(arc
							(start -0.2032 0.2286)
							(mid -0.239121 0.213721)
							(end -0.254 0.1778)
						)
					)
					(width 0)
					(fill yes)
				)
			)
		)
	)
	(footprint ""
		(layer "F.Cu")
		(at 15.8496 -56.0832 -90)
		(property "Reference" "PR63"
			(at 0 0 270)
			(layer "F.SilkS")
			(hide yes)
			(effects
				(font
					(size 1.27 1.27)
				)
			)
		)
		(property "Value" "0R2J-2-GP"
			(at 1.7907 -1.1176 270)
			(unlocked yes)
			(layer "F.Fab")
			(hide yes)
			(effects
				(font
					(size 1.016 1.016)
					(thickness 0.1524)
				)
			)
		)
		(property "Device Type" "R402H16"
			(at 1.7907 -2.6416 270)
			(unlocked yes)
			(layer "F.Fab")
			(hide yes)
			(effects
				(font
					(size 1.016 1.016)
					(thickness 0.1524)
				)
			)
		)
		(duplicate_pad_numbers_are_jumpers no)
		(fp_rect
			(start -0.381 0.8382)
			(end 0.381 -0.8382)
			(stroke
				(width 0)
				(type default)
			)
			(fill no)
			(layer "F.CrtYd")
		)
		(fp_rect
			(start -0.381 0.8382)
			(end 0.381 -0.8382)
			(stroke
				(width 0)
				(type default)
			)
			(fill no)
			(layer "F.Fab")
		)
		(pad "1" smd custom
			(at 0 -0.4318 270)
			(size 0.127 0.127)
			(layers "F.Cu" "F.Mask" "F.Paste")
			(net "PWRGD_R_PVCCP")
			(options
				(clearance outline)
				(anchor circle)
			)
			(primitives
				(gr_poly
					(pts
						(arc
							(start -0.2032 -0.2794)
							(mid -0.239121 -0.264521)
							(end -0.254 -0.2286)
						)
						(arc
							(start -0.254 0.2286)
							(mid -0.239121 0.264521)
							(end -0.2032 0.2794)
						)
						(arc
							(start 0.2032 0.2794)
							(mid 0.239121 0.264521)
							(end 0.254 0.2286)
						)
						(arc
							(start 0.254 -0.2286)
							(mid 0.239121 -0.264521)
							(end 0.2032 -0.2794)
						)
					)
					(width 0)
					(fill yes)
				)
			)
		)
		(pad "2" smd custom
			(at 0 0.4318 270)
			(size 0.127 0.127)
			(layers "F.Cu" "F.Mask" "F.Paste")
			(net "PWRGD_PVCCP_VNN_PG")
			(options
				(clearance outline)
				(anchor circle)
			)
			(primitives
				(gr_poly
					(pts
						(arc
							(start -0.2032 -0.2794)
							(mid -0.239121 -0.264521)
							(end -0.254 -0.2286)
						)
						(arc
							(start -0.254 0.2286)
							(mid -0.239121 0.264521)
							(end -0.2032 0.2794)
						)
						(arc
							(start 0.2032 0.2794)
							(mid 0.239121 0.264521)
							(end 0.254 0.2286)
						)
						(arc
							(start 0.254 -0.2286)
							(mid 0.239121 -0.264521)
							(end 0.2032 -0.2794)
						)
					)
					(width 0)
					(fill yes)
				)
			)
		)
	)
	(footprint ""
		(layer "F.Cu")
		(at 167.894 -28.321 90)
		(property "Reference" "PR136"
			(at 0 0 90)
			(layer "F.SilkS")
			(hide yes)
			(effects
				(font
					(size 1.27 1.27)
				)
			)
		)
		(property "Value" "0R3J-6-GP"
			(at -0.0254 -2.5146 90)
			(unlocked yes)
			(layer "F.Fab")
			(hide yes)
			(effects
				(font
					(size 1.016 1.016)
					(thickness 0.1524)
				)
			)
		)
		(property "Device Type" "R603H22"
			(at -0.0254 -4.0386 90)
			(unlocked yes)
			(layer "F.Fab")
			(hide yes)
			(effects
				(font
					(size 1.016 1.016)
					(thickness 0.1524)
				)
			)
		)
		(duplicate_pad_numbers_are_jumpers no)
		(fp_line
			(start 0.4318 0)
			(end 0.2032 0)
			(stroke
				(width 0.2032)
				(type default)
			)
			(layer "F.SilkS")
		)
		(fp_line
			(start -0.2032 0)
			(end -0.4191 0)
			(stroke
				(width 0.2032)
				(type default)
			)
			(layer "F.SilkS")
		)
		(fp_rect
			(start -0.635 1.1811)
			(end 0.635 -1.1811)
			(stroke
				(width 0)
				(type default)
			)
			(fill no)
			(layer "F.CrtYd")
		)
		(fp_rect
			(start -0.635 1.1811)
			(end 0.635 -1.1811)
			(stroke
				(width 0)
				(type default)
			)
			(fill no)
			(layer "F.Fab")
		)
		(pad "1" smd custom
			(at 0 -0.6604 90)
			(size 0.19685 0.19685)
			(layers "F.Cu" "F.Mask" "F.Paste")
			(net "P1V2_FPGA_D")
			(options
				(clearance outline)
				(anchor circle)
			)
			(primitives
				(gr_poly
					(pts
						(arc
							(start 0.508 -0.2921)
							(mid 0.478242 -0.363942)
							(end 0.4064 -0.3937)
						)
						(arc
							(start -0.4064 -0.3937)
							(mid -0.478242 -0.363942)
							(end -0.508 -0.2921)
						)
						(arc
							(start -0.508 0.2921)
							(mid -0.478242 0.363942)
							(end -0.4064 0.3937)
						)
						(arc
							(start 0.4064 0.3937)
							(mid 0.478242 0.363942)
							(end 0.508 0.2921)
						)
					)
					(width 0)
					(fill yes)
				)
			)
		)
		(pad "2" smd custom
			(at 0 0.6604 90)
			(size 0.19685 0.19685)
			(layers "F.Cu" "F.Mask" "F.Paste")
			(net "P1V2_STBY_LDO_OUT2")
			(options
				(clearance outline)
				(anchor circle)
			)
			(primitives
				(gr_poly
					(pts
						(arc
							(start 0.508 -0.2921)
							(mid 0.478242 -0.363942)
							(end 0.4064 -0.3937)
						)
						(arc
							(start -0.4064 -0.3937)
							(mid -0.478242 -0.363942)
							(end -0.508 -0.2921)
						)
						(arc
							(start -0.508 0.2921)
							(mid -0.478242 0.363942)
							(end -0.4064 0.3937)
						)
						(arc
							(start 0.4064 0.3937)
							(mid 0.478242 0.363942)
							(end 0.508 0.2921)
						)
					)
					(width 0)
					(fill yes)
				)
			)
		)
	)
	(footprint ""
		(layer "F.Cu")
		(at 79.121 -65.913 180)
		(property "Reference" "R178"
			(at 0 0 180)
			(layer "F.SilkS")
			(hide yes)
			(effects
				(font
					(size 1.27 1.27)
				)
			)
		)
		(property "Value" "4K7R2F-GP"
			(at 1.7907 -1.1176 180)
			(unlocked yes)
			(layer "F.Fab")
			(hide yes)
			(effects
				(font
					(size 1.016 1.016)
					(thickness 0.1524)
				)
			)
		)
		(property "Device Type" "R402H16"
			(at 1.7907 -2.6416 180)
			(unlocked yes)
			(layer "F.Fab")
			(hide yes)
			(effects
				(font
					(size 1.016 1.016)
					(thickness 0.1524)
				)
			)
		)
		(duplicate_pad_numbers_are_jumpers no)
		(fp_rect
			(start -0.381 0.8382)
			(end 0.381 -0.8382)
			(stroke
				(width 0)
				(type default)
			)
			(fill no)
			(layer "F.CrtYd")
		)
		(fp_rect
			(start -0.381 0.8382)
			(end 0.381 -0.8382)
			(stroke
				(width 0)
				(type default)
			)
			(fill no)
			(layer "F.Fab")
		)
		(pad "1" smd custom
			(at 0 -0.4318 180)
			(size 0.127 0.127)
			(layers "F.Cu" "F.Mask" "F.Paste")
			(net "VOL1_SEN_ADDR1")
			(options
				(clearance outline)
				(anchor circle)
			)
			(primitives
				(gr_poly
					(pts
						(arc
							(start -0.2032 -0.2794)
							(mid -0.239121 -0.264521)
							(end -0.254 -0.2286)
						)
						(arc
							(start -0.254 0.2286)
							(mid -0.239121 0.264521)
							(end -0.2032 0.2794)
						)
						(arc
							(start 0.2032 0.2794)
							(mid 0.239121 0.264521)
							(end 0.254 0.2286)
						)
						(arc
							(start 0.254 -0.2286)
							(mid 0.239121 -0.264521)
							(end 0.2032 -0.2794)
						)
					)
					(width 0)
					(fill yes)
				)
			)
		)
		(pad "2" smd custom
			(at 0 0.4318 180)
			(size 0.127 0.127)
			(layers "F.Cu" "F.Mask" "F.Paste")
			(net "GND")
			(options
				(clearance outline)
				(anchor circle)
			)
			(primitives
				(gr_poly
					(pts
						(arc
							(start -0.2032 -0.2794)
							(mid -0.239121 -0.264521)
							(end -0.254 -0.2286)
						)
						(arc
							(start -0.254 0.2286)
							(mid -0.239121 0.264521)
							(end -0.2032 0.2794)
						)
						(arc
							(start 0.2032 0.2794)
							(mid 0.239121 0.264521)
							(end 0.254 0.2286)
						)
						(arc
							(start 0.254 -0.2286)
							(mid 0.239121 -0.264521)
							(end 0.2032 -0.2794)
						)
					)
					(width 0)
					(fill yes)
				)
			)
		)
	)
)
